G04 ================== begin FILE IDENTIFICATION RECORD ==================*
G04 Layout Name:  F:/<user>/2022/FB/R4006-TIMING/brd/gerber-3/R4006-B0001-02_R01.brd*
G04 Film Name:    R4006-B0001-02_R01_BD_10-9*
G04 File Format:  Gerber RS274X*
G04 File Origin:  Cadence Allegro 17.2-S079*
G04 Origin Date:  Fri Feb 25 18:14:44 2022*
G04 *
G04 Layer:  BOARD GEOMETRY/OUTLINE*
G04 Layer:  MANUFACTURING/NCBACKDRILL-10-9*
G04 *
G04 Offset:    (0.00 0.00)*
G04 Mirror:    No*
G04 Mode:      Positive*
G04 Rotation:  0*
G04 FullContactRelief:  No*
G04 UndefLineWidth:     6.00*
G04 ================== end FILE IDENTIFICATION RECORD ====================*
%FSLAX55Y55*MOIN*%
%IR0*IPPOS*OFA0.00000B0.00000*MIA0B0*SFA1.00000B1.00000*%
%AMMACRO10*
1,1,.006,0.0,.025*
20,1,.006,0.0,.025,.004341,.02462,0.0*
1,1,.006,.004341,.02462*
20,1,.006,.004341,.02462,.008551,.023492,0.0*
1,1,.006,.008551,.023492*
20,1,.006,.008551,.023492,.0125,.021651,0.0*
1,1,.006,.0125,.021651*
20,1,.006,.0125,.021651,.01607,.019151,0.0*
1,1,.006,.01607,.019151*
20,1,.006,.01607,.019151,.019151,.01607,0.0*
1,1,.006,.019151,.01607*
20,1,.006,.019151,.01607,.021651,.0125,0.0*
1,1,.006,.021651,.0125*
20,1,.006,.021651,.0125,.023492,.008551,0.0*
1,1,.006,.023492,.008551*
20,1,.006,.023492,.008551,.02462,.004341,0.0*
1,1,.006,.02462,.004341*
20,1,.006,.02462,.004341,.025,0.0,0.0*
1,1,.006,.025,0.0*
20,1,.006,.025,0.0,.02462,-.004341,0.0*
1,1,.006,.02462,-.004341*
20,1,.006,.02462,-.004341,.023492,-.008551,0.0*
1,1,.006,.023492,-.008551*
20,1,.006,.023492,-.008551,.021651,-.0125,0.0*
1,1,.006,.021651,-.0125*
20,1,.006,.021651,-.0125,.019151,-.01607,0.0*
1,1,.006,.019151,-.01607*
20,1,.006,.019151,-.01607,.01607,-.019151,0.0*
1,1,.006,.01607,-.019151*
20,1,.006,.01607,-.019151,.0125,-.021651,0.0*
1,1,.006,.0125,-.021651*
20,1,.006,.0125,-.021651,.008551,-.023492,0.0*
1,1,.006,.008551,-.023492*
20,1,.006,.008551,-.023492,.004341,-.02462,0.0*
1,1,.006,.004341,-.02462*
20,1,.006,.004341,-.02462,0.0,-.025,0.0*
1,1,.006,0.0,-.025*
20,1,.006,0.0,-.025,-.004341,-.02462,0.0*
1,1,.006,-.004341,-.02462*
20,1,.006,-.004341,-.02462,-.008551,-.023492,0.0*
1,1,.006,-.008551,-.023492*
20,1,.006,-.008551,-.023492,-.0125,-.021651,0.0*
1,1,.006,-.0125,-.021651*
20,1,.006,-.0125,-.021651,-.01607,-.019151,0.0*
1,1,.006,-.01607,-.019151*
20,1,.006,-.01607,-.019151,-.019151,-.01607,0.0*
1,1,.006,-.019151,-.01607*
20,1,.006,-.019151,-.01607,-.021651,-.0125,0.0*
1,1,.006,-.021651,-.0125*
20,1,.006,-.021651,-.0125,-.023492,-.008551,0.0*
1,1,.006,-.023492,-.008551*
20,1,.006,-.023492,-.008551,-.02462,-.004341,0.0*
1,1,.006,-.02462,-.004341*
20,1,.006,-.02462,-.004341,-.025,0.0,0.0*
1,1,.006,-.025,0.0*
20,1,.006,-.025,0.0,-.02462,.004341,0.0*
1,1,.006,-.02462,.004341*
20,1,.006,-.02462,.004341,-.023492,.008551,0.0*
1,1,.006,-.023492,.008551*
20,1,.006,-.023492,.008551,-.021651,.0125,0.0*
1,1,.006,-.021651,.0125*
20,1,.006,-.021651,.0125,-.019151,.01607,0.0*
1,1,.006,-.019151,.01607*
20,1,.006,-.019151,.01607,-.01607,.019151,0.0*
1,1,.006,-.01607,.019151*
20,1,.006,-.01607,.019151,-.0125,.021651,0.0*
1,1,.006,-.0125,.021651*
20,1,.006,-.0125,.021651,-.008551,.023492,0.0*
1,1,.006,-.008551,.023492*
20,1,.006,-.008551,.023492,-.004341,.02462,0.0*
1,1,.006,-.004341,.02462*
20,1,.006,-.004341,.02462,0.0,.025,0.0*
1,1,.006,0.0,.025*
1,1,.006,-.01042,-.0125*
20,1,.006,-.01042,-.0125,0.0,.0125,0.0*
1,1,.006,0.0,.0125*
20,1,.006,0.0,.0125,.01042,-.0125,0.0*
1,1,.006,.01042,-.0125*
1,1,.006,.00667,-.00375*
20,1,.006,.00667,-.00375,-.00667,-.00375,0.0*
1,1,.006,-.00667,-.00375*
%
%ADD10MACRO10*%
%ADD11C,.006*%
G75*
%LPD*%
G75*
G54D10*
X73500Y357500D03*
X70300D03*
X110500Y382500D03*
X107300D03*
X341799Y108500D03*
X337500Y116200D03*
Y119400D03*
X344999Y108500D03*
X351464Y104707D03*
X354664D03*
X365700Y92000D03*
X362500D03*
X391130Y143005D03*
X387193D03*
X395067Y146942D03*
Y154816D03*
X391130Y150879D03*
X387193D03*
X399005Y146942D03*
Y154816D03*
X469870Y146942D03*
X473807D03*
Y139067D03*
Y135130D03*
X619961Y224474D03*
Y227674D03*
X928350Y-254757D03*
G54D11*
G01X658071Y284646D02*
G03X660039Y286614I0J1968D01*
G01Y433661D01*
G03X656102Y437598I-3937J0D01*
G01X3937D01*
G03X0Y433661I0J-3937D01*
G01Y21654D01*
G03X3937Y17717I3937J0D01*
G01X55118D01*
G03X59055Y21654I0J3937D01*
G01Y46260D01*
G02X62992Y50197I3937J0D01*
G01X127362D01*
G02X131299Y46260I0J-3937D01*
G01Y21654D01*
G03X135236Y17717I3937J0D01*
G01X158858D01*
G03X162795Y21654I0J3937D01*
G01Y43012D01*
G02X177165I7185J0D01*
G01Y1969D01*
X179134Y0D01*
X219291D01*
X221260Y1969D01*
Y29331D01*
G02X228740I3740J0D01*
G01Y1969D01*
X230709Y0D01*
X310236D01*
X312205Y1969D01*
Y46260D01*
G02X316142Y50197I3937J0D01*
G01X656102D01*
G03X660039Y54134I0J3937D01*
G01Y237500D01*
G03X658071Y239469I-1969J1D01*
G01X657211D01*
G02X655243Y241437I0J1968D01*
G01Y282677D01*
G02X657211Y284646I1968J0D01*
G01X658071D01*
G01X886035Y-375590D02*
X890065D01*
G01X908820Y-379757D02*
Y-367257D01*
X912850Y-377674D01*
X916880Y-367257D01*
Y-379757D01*
G01X922305D02*
Y-367257D01*
X928195D01*
G01X926025Y-373299D02*
X922305D01*
G01X938580Y-373507D02*
X941680D01*
Y-377257D01*
X940750Y-378507D01*
X939665Y-379340D01*
X938115Y-379757D01*
X936565Y-379340D01*
X935480Y-378507D01*
X934550Y-377257D01*
X933930Y-375799D01*
X933620Y-374132D01*
Y-372674D01*
X933930Y-371424D01*
X934550Y-369965D01*
X935480Y-368715D01*
X936410Y-367882D01*
X937650Y-367257D01*
X938735D01*
X939975Y-367674D01*
X940905Y-368507D01*
G01X945400Y-383924D02*
X954700D01*
G01X959195Y-378091D02*
X960435Y-379132D01*
X961830Y-379757D01*
X963070D01*
X964310Y-379132D01*
X965240Y-378091D01*
X965705Y-376632D01*
X965395Y-375174D01*
X964620Y-373924D01*
X963225Y-373090D01*
X961365Y-372674D01*
X960280Y-371840D01*
X959815Y-370382D01*
X960125Y-368924D01*
X960900Y-367882D01*
X961985Y-367257D01*
X963070D01*
X964155Y-367674D01*
X965085Y-368715D01*
G01X974850Y-367257D02*
Y-379757D01*
G01X971285Y-367257D02*
X978415D01*
G01X983840D02*
Y-376215D01*
X984460Y-378091D01*
X985700Y-379340D01*
X987250Y-379757D01*
X988800Y-379340D01*
X990040Y-378091D01*
X990660Y-376215D01*
Y-367257D01*
G01X1000890Y-373090D02*
X1001510Y-372465D01*
X1001975Y-371424D01*
X1002285Y-369965D01*
X1001975Y-368715D01*
X1001355Y-367882D01*
X1000270Y-367257D01*
X996085D01*
Y-379757D01*
X1001200D01*
X1002285Y-378924D01*
X1002905Y-377674D01*
X1003215Y-376215D01*
X1002905Y-374757D01*
X1001975Y-373507D01*
X1000890Y-373090D01*
X996085D01*
G01X1024450Y-380174D02*
X1024140Y-379965D01*
Y-379549D01*
X1024450Y-379340D01*
X1024760Y-379549D01*
Y-379965D01*
X1024450Y-380174D01*
G01Y-374549D02*
X1024140Y-374340D01*
Y-373924D01*
X1024450Y-373715D01*
X1024760Y-373924D01*
Y-374340D01*
X1024450Y-374549D01*
G01X1045220Y-379757D02*
Y-367257D01*
X1049250Y-377674D01*
X1053280Y-367257D01*
Y-379757D01*
G01X1057775D02*
X1061650Y-367257D01*
X1065525Y-379757D01*
G01X1064130Y-375382D02*
X1059170D01*
G01X1070485Y-379757D02*
Y-367257D01*
X1077615Y-379757D01*
Y-367257D01*
G01X1083040D02*
Y-376215D01*
X1083660Y-378091D01*
X1084900Y-379340D01*
X1086450Y-379757D01*
X1088000Y-379340D01*
X1089240Y-378091D01*
X1089860Y-376215D01*
Y-367257D01*
G01X1095905Y-379757D02*
Y-367257D01*
X1101795D01*
G01X1099625Y-373299D02*
X1095905D01*
G01X1107375Y-379757D02*
X1111250Y-367257D01*
X1115125Y-379757D01*
G01X1113730Y-375382D02*
X1108770D01*
G01X1127060Y-368299D02*
X1126130Y-367674D01*
X1125045Y-367257D01*
X1123805D01*
X1122410Y-367882D01*
X1121325Y-368924D01*
X1120550Y-370174D01*
X1119930Y-372257D01*
X1119775Y-374132D01*
X1120085Y-376007D01*
X1120550Y-377257D01*
X1121480Y-378507D01*
X1122565Y-379340D01*
X1123650Y-379757D01*
X1124735D01*
X1125820Y-379340D01*
X1126750Y-378716D01*
X1127525Y-377882D01*
G01X1136050Y-367257D02*
Y-379757D01*
G01X1132485Y-367257D02*
X1139615D01*
G01X1145040D02*
Y-376215D01*
X1145660Y-378091D01*
X1146900Y-379340D01*
X1148450Y-379757D01*
X1150000Y-379340D01*
X1151240Y-378091D01*
X1151860Y-376215D01*
Y-367257D01*
G01X1157750Y-379757D02*
Y-367257D01*
X1161625D01*
X1162865Y-367882D01*
X1163640Y-368715D01*
X1163950Y-370382D01*
X1163640Y-372049D01*
X1162710Y-373090D01*
X1161625Y-373715D01*
X1157750D01*
G01X1161625D02*
X1163950Y-379757D01*
G01X1171390Y-367257D02*
X1175110D01*
G01X1173250D02*
Y-379757D01*
G01X1171390D02*
X1175110D01*
G01X1182085D02*
Y-367257D01*
X1189215Y-379757D01*
Y-367257D01*
G01X1198980Y-373507D02*
X1202080D01*
Y-377257D01*
X1201150Y-378507D01*
X1200065Y-379340D01*
X1198515Y-379757D01*
X1196965Y-379340D01*
X1195880Y-378507D01*
X1194950Y-377257D01*
X1194330Y-375799D01*
X1194020Y-374132D01*
Y-372674D01*
X1194330Y-371424D01*
X1194950Y-369965D01*
X1195880Y-368715D01*
X1196810Y-367882D01*
X1198050Y-367257D01*
X1199135D01*
X1200375Y-367674D01*
X1201305Y-368507D01*
G01X1219595Y-378091D02*
X1220835Y-379132D01*
X1222230Y-379757D01*
X1223470D01*
X1224710Y-379132D01*
X1225640Y-378091D01*
X1226105Y-376632D01*
X1225795Y-375174D01*
X1225020Y-373924D01*
X1223625Y-373090D01*
X1221765Y-372674D01*
X1220680Y-371840D01*
X1220215Y-370382D01*
X1220525Y-368924D01*
X1221300Y-367882D01*
X1222385Y-367257D01*
X1223470D01*
X1224555Y-367674D01*
X1225485Y-368715D01*
G01X1235250Y-367257D02*
Y-379757D01*
G01X1231685Y-367257D02*
X1238815D01*
G01X1244240D02*
Y-376215D01*
X1244860Y-378091D01*
X1246100Y-379340D01*
X1247650Y-379757D01*
X1249200Y-379340D01*
X1250440Y-378091D01*
X1251060Y-376215D01*
Y-367257D01*
G01X1261290Y-373090D02*
X1261910Y-372465D01*
X1262375Y-371424D01*
X1262685Y-369965D01*
X1262375Y-368715D01*
X1261755Y-367882D01*
X1260670Y-367257D01*
X1256485D01*
Y-379757D01*
X1261600D01*
X1262685Y-378924D01*
X1263305Y-377674D01*
X1263615Y-376215D01*
X1263305Y-374757D01*
X1262375Y-373507D01*
X1261290Y-373090D01*
X1256485D01*
G01X1281750Y-367257D02*
Y-379757D01*
X1287950D01*
G01X1300350D02*
X1294150D01*
Y-367257D01*
X1300350D01*
G01X1297870Y-373299D02*
X1294150D01*
G01X1306085Y-379757D02*
Y-367257D01*
X1313215Y-379757D01*
Y-367257D01*
G01X1322980Y-373507D02*
X1326080D01*
Y-377257D01*
X1325150Y-378507D01*
X1324065Y-379340D01*
X1322515Y-379757D01*
X1320965Y-379340D01*
X1319880Y-378507D01*
X1318950Y-377257D01*
X1318330Y-375799D01*
X1318020Y-374132D01*
Y-372674D01*
X1318330Y-371424D01*
X1318950Y-369965D01*
X1319880Y-368715D01*
X1320810Y-367882D01*
X1322050Y-367257D01*
X1323135D01*
X1324375Y-367674D01*
X1325305Y-368507D01*
G01X1334450Y-367257D02*
Y-379757D01*
G01X1330885Y-367257D02*
X1338015D01*
G01X1343595Y-379757D02*
Y-367257D01*
G01X1350105D02*
Y-379757D01*
G01Y-373507D02*
X1343595D01*
G01X1045995Y-359341D02*
X1047235Y-360382D01*
X1048630Y-361007D01*
X1049870D01*
X1051110Y-360382D01*
X1052040Y-359341D01*
X1052505Y-357882D01*
X1052195Y-356424D01*
X1051420Y-355174D01*
X1050025Y-354340D01*
X1048165Y-353924D01*
X1047080Y-353090D01*
X1046615Y-351632D01*
X1046925Y-350174D01*
X1047700Y-349132D01*
X1048785Y-348507D01*
X1049870D01*
X1050955Y-348924D01*
X1051885Y-349965D01*
G01X1058240Y-348507D02*
Y-357465D01*
X1058860Y-359341D01*
X1060100Y-360590D01*
X1061650Y-361007D01*
X1063200Y-360590D01*
X1064440Y-359341D01*
X1065060Y-357465D01*
Y-348507D01*
G01X1070950Y-361007D02*
Y-348507D01*
X1074825D01*
X1076065Y-349132D01*
X1076840Y-349965D01*
X1077150Y-351632D01*
X1076840Y-353299D01*
X1075910Y-354340D01*
X1074825Y-354965D01*
X1070950D01*
G01X1074825D02*
X1077150Y-361007D01*
G01X1083505D02*
Y-348507D01*
X1089395D01*
G01X1087225Y-354549D02*
X1083505D01*
G01X1094975Y-361007D02*
X1098850Y-348507D01*
X1102725Y-361007D01*
G01X1101330Y-356632D02*
X1096370D01*
G01X1114660Y-349549D02*
X1113730Y-348924D01*
X1112645Y-348507D01*
X1111405D01*
X1110010Y-349132D01*
X1108925Y-350174D01*
X1108150Y-351424D01*
X1107530Y-353507D01*
X1107375Y-355382D01*
X1107685Y-357257D01*
X1108150Y-358507D01*
X1109080Y-359757D01*
X1110165Y-360590D01*
X1111250Y-361007D01*
X1112335D01*
X1113420Y-360590D01*
X1114350Y-359966D01*
X1115125Y-359132D01*
G01X1126750Y-361007D02*
X1120550D01*
Y-348507D01*
X1126750D01*
G01X1124270Y-354549D02*
X1120550D01*
G01X1148450Y-361007D02*
X1147210Y-360799D01*
X1146125Y-359966D01*
X1145195Y-358715D01*
X1144575Y-357257D01*
X1144265Y-355590D01*
Y-353924D01*
X1144575Y-352257D01*
X1145195Y-350799D01*
X1146125Y-349549D01*
X1147210Y-348715D01*
X1148450Y-348507D01*
X1149690Y-348715D01*
X1150775Y-349549D01*
X1151705Y-350799D01*
X1152325Y-352257D01*
X1152635Y-353924D01*
Y-355590D01*
X1152325Y-357257D01*
X1151705Y-358715D01*
X1150775Y-359966D01*
X1149690Y-360799D01*
X1148450Y-361007D01*
G01X1157905D02*
Y-348507D01*
X1163795D01*
G01X1161625Y-354549D02*
X1157905D01*
G01X1181620Y-361007D02*
Y-348507D01*
X1185650Y-358924D01*
X1189680Y-348507D01*
Y-361007D01*
G01X1194640Y-348507D02*
Y-357465D01*
X1195260Y-359341D01*
X1196500Y-360590D01*
X1198050Y-361007D01*
X1199600Y-360590D01*
X1200840Y-359341D01*
X1201460Y-357465D01*
Y-348507D01*
G01X1207195Y-359341D02*
X1208435Y-360382D01*
X1209830Y-361007D01*
X1211070D01*
X1212310Y-360382D01*
X1213240Y-359341D01*
X1213705Y-357882D01*
X1213395Y-356424D01*
X1212620Y-355174D01*
X1211225Y-354340D01*
X1209365Y-353924D01*
X1208280Y-353090D01*
X1207815Y-351632D01*
X1208125Y-350174D01*
X1208900Y-349132D01*
X1209985Y-348507D01*
X1211070D01*
X1212155Y-348924D01*
X1213085Y-349965D01*
G01X1222850Y-348507D02*
Y-361007D01*
G01X1219285Y-348507D02*
X1226415D01*
G01X1233235Y-356840D02*
X1237265D01*
G01X1244085Y-361007D02*
Y-348507D01*
X1251215Y-361007D01*
Y-348507D01*
G01X1260050Y-361007D02*
X1258810Y-360799D01*
X1257725Y-359966D01*
X1256795Y-358715D01*
X1256175Y-357257D01*
X1255865Y-355590D01*
Y-353924D01*
X1256175Y-352257D01*
X1256795Y-350799D01*
X1257725Y-349549D01*
X1258810Y-348715D01*
X1260050Y-348507D01*
X1261290Y-348715D01*
X1262375Y-349549D01*
X1263305Y-350799D01*
X1263925Y-352257D01*
X1264235Y-353924D01*
Y-355590D01*
X1263925Y-357257D01*
X1263305Y-358715D01*
X1262375Y-359966D01*
X1261290Y-360799D01*
X1260050Y-361007D01*
G01X1272450Y-348507D02*
Y-361007D01*
G01X1268885Y-348507D02*
X1276015D01*
G01X1282835Y-356840D02*
X1286865D01*
G01X1300660Y-349549D02*
X1299730Y-348924D01*
X1298645Y-348507D01*
X1297405D01*
X1296010Y-349132D01*
X1294925Y-350174D01*
X1294150Y-351424D01*
X1293530Y-353507D01*
X1293375Y-355382D01*
X1293685Y-357257D01*
X1294150Y-358507D01*
X1295080Y-359757D01*
X1296165Y-360590D01*
X1297250Y-361007D01*
X1298335D01*
X1299420Y-360590D01*
X1300350Y-359966D01*
X1301125Y-359132D01*
G01X1306240Y-348507D02*
Y-357465D01*
X1306860Y-359341D01*
X1308100Y-360590D01*
X1309650Y-361007D01*
X1311200Y-360590D01*
X1312440Y-359341D01*
X1313060Y-357465D01*
Y-348507D01*
G01X1322050D02*
Y-361007D01*
G01X1318485Y-348507D02*
X1325615D01*
G01X1332435Y-356840D02*
X1336465D01*
G01X1343750Y-348507D02*
Y-361007D01*
X1349950D01*
G01X1355375D02*
X1359250Y-348507D01*
X1363125Y-361007D01*
G01X1361730Y-356632D02*
X1356770D01*
G01X1371650Y-361007D02*
Y-355382D01*
X1368550Y-348507D01*
G01X1374750D02*
X1371650Y-355382D01*
G01X1387150Y-361007D02*
X1380950D01*
Y-348507D01*
X1387150D01*
G01X1384670Y-354549D02*
X1380950D01*
G01X1393350Y-361007D02*
Y-348507D01*
X1397225D01*
X1398465Y-349132D01*
X1399240Y-349965D01*
X1399550Y-351632D01*
X1399240Y-353299D01*
X1398310Y-354340D01*
X1397225Y-354965D01*
X1393350D01*
G01X1397225D02*
X1399550Y-361007D01*
G01X886035Y-338090D02*
X890065D01*
G01X908820Y-342257D02*
Y-329757D01*
X912850Y-340174D01*
X916880Y-329757D01*
Y-342257D01*
G01X921375D02*
X925250Y-329757D01*
X929125Y-342257D01*
G01X927730Y-337882D02*
X922770D01*
G01X934395Y-342257D02*
X940905Y-329757D01*
G01X934395D02*
X940905Y-342257D01*
G01X945400Y-346424D02*
X954700D01*
G01X959040Y-342257D02*
Y-329757D01*
X962140D01*
X963380Y-330382D01*
X964310Y-331215D01*
X965085Y-332465D01*
X965705Y-333924D01*
X965860Y-336007D01*
X965705Y-338090D01*
X965085Y-339549D01*
X964310Y-340799D01*
X963380Y-341632D01*
X962140Y-342257D01*
X959040D01*
G01X977950D02*
X971750D01*
Y-329757D01*
X977950D01*
G01X975470Y-335799D02*
X971750D01*
G01X984150Y-342257D02*
Y-329757D01*
X987870D01*
X989110Y-330382D01*
X990040Y-331840D01*
X990350Y-333507D01*
X990040Y-335174D01*
X989265Y-336424D01*
X987870Y-337049D01*
X984150D01*
G01X999650Y-329757D02*
Y-342257D01*
G01X996085Y-329757D02*
X1003215D01*
G01X1008795Y-342257D02*
Y-329757D01*
G01X1015305D02*
Y-342257D01*
G01Y-336007D02*
X1008795D01*
G01X1024450Y-342674D02*
X1024140Y-342465D01*
Y-342049D01*
X1024450Y-341840D01*
X1024760Y-342049D01*
Y-342465D01*
X1024450Y-342674D01*
G01Y-337049D02*
X1024140Y-336840D01*
Y-336424D01*
X1024450Y-336215D01*
X1024760Y-336424D01*
Y-336840D01*
X1024450Y-337049D01*
G01X1045840Y-342257D02*
Y-329757D01*
X1048940D01*
X1050180Y-330382D01*
X1051110Y-331215D01*
X1051885Y-332465D01*
X1052505Y-333924D01*
X1052660Y-336007D01*
X1052505Y-338090D01*
X1051885Y-339549D01*
X1051110Y-340799D01*
X1050180Y-341632D01*
X1048940Y-342257D01*
X1045840D01*
G01X1064750D02*
X1058550D01*
Y-329757D01*
X1064750D01*
G01X1062270Y-335799D02*
X1058550D01*
G01X1070950Y-342257D02*
Y-329757D01*
X1074670D01*
X1075910Y-330382D01*
X1076840Y-331840D01*
X1077150Y-333507D01*
X1076840Y-335174D01*
X1076065Y-336424D01*
X1074670Y-337049D01*
X1070950D01*
G01X1086450Y-329757D02*
Y-342257D01*
G01X1082885Y-329757D02*
X1090015D01*
G01X1095595Y-342257D02*
Y-329757D01*
G01X1102105D02*
Y-342257D01*
G01Y-336007D02*
X1095595D01*
G01X1120705Y-342257D02*
Y-329757D01*
X1126595D01*
G01X1124425Y-335799D02*
X1120705D01*
G01X1132950Y-342257D02*
Y-329757D01*
X1136825D01*
X1138065Y-330382D01*
X1138840Y-331215D01*
X1139150Y-332882D01*
X1138840Y-334549D01*
X1137910Y-335590D01*
X1136825Y-336215D01*
X1132950D01*
G01X1136825D02*
X1139150Y-342257D01*
G01X1148450D02*
X1147210Y-342049D01*
X1146125Y-341216D01*
X1145195Y-339965D01*
X1144575Y-338507D01*
X1144265Y-336840D01*
Y-335174D01*
X1144575Y-333507D01*
X1145195Y-332049D01*
X1146125Y-330799D01*
X1147210Y-329965D01*
X1148450Y-329757D01*
X1149690Y-329965D01*
X1150775Y-330799D01*
X1151705Y-332049D01*
X1152325Y-333507D01*
X1152635Y-335174D01*
Y-336840D01*
X1152325Y-338507D01*
X1151705Y-339965D01*
X1150775Y-341216D01*
X1149690Y-342049D01*
X1148450Y-342257D01*
G01X1156820D02*
Y-329757D01*
X1160850Y-340174D01*
X1164880Y-329757D01*
Y-342257D01*
G01X1182395Y-340591D02*
X1183635Y-341632D01*
X1185030Y-342257D01*
X1186270D01*
X1187510Y-341632D01*
X1188440Y-340591D01*
X1188905Y-339132D01*
X1188595Y-337674D01*
X1187820Y-336424D01*
X1186425Y-335590D01*
X1184565Y-335174D01*
X1183480Y-334340D01*
X1183015Y-332882D01*
X1183325Y-331424D01*
X1184100Y-330382D01*
X1185185Y-329757D01*
X1186270D01*
X1187355Y-330174D01*
X1188285Y-331215D01*
G01X1198050Y-329757D02*
Y-342257D01*
G01X1194485Y-329757D02*
X1201615D01*
G01X1206575Y-342257D02*
X1210450Y-329757D01*
X1214325Y-342257D01*
G01X1212930Y-337882D02*
X1207970D01*
G01X1219750Y-342257D02*
Y-329757D01*
X1223625D01*
X1224865Y-330382D01*
X1225640Y-331215D01*
X1225950Y-332882D01*
X1225640Y-334549D01*
X1224710Y-335590D01*
X1223625Y-336215D01*
X1219750D01*
G01X1223625D02*
X1225950Y-342257D01*
G01X1235250Y-329757D02*
Y-342257D01*
G01X1231685Y-329757D02*
X1238815D01*
G01X1256950D02*
Y-342257D01*
X1263150D01*
G01X1268575D02*
X1272450Y-329757D01*
X1276325Y-342257D01*
G01X1274930Y-337882D02*
X1269970D01*
G01X1284850Y-342257D02*
Y-336632D01*
X1281750Y-329757D01*
G01X1287950D02*
X1284850Y-336632D01*
G01X1300350Y-342257D02*
X1294150D01*
Y-329757D01*
X1300350D01*
G01X1297870Y-335799D02*
X1294150D01*
G01X1306550Y-342257D02*
Y-329757D01*
X1310425D01*
X1311665Y-330382D01*
X1312440Y-331215D01*
X1312750Y-332882D01*
X1312440Y-334549D01*
X1311510Y-335590D01*
X1310425Y-336215D01*
X1306550D01*
G01X1310425D02*
X1312750Y-342257D01*
G01X1334450Y-329757D02*
Y-342257D01*
G01X1330885Y-329757D02*
X1338015D01*
G01X1346850Y-342257D02*
X1345610Y-342049D01*
X1344525Y-341216D01*
X1343595Y-339965D01*
X1342975Y-338507D01*
X1342665Y-336840D01*
Y-335174D01*
X1342975Y-333507D01*
X1343595Y-332049D01*
X1344525Y-330799D01*
X1345610Y-329965D01*
X1346850Y-329757D01*
X1348090Y-329965D01*
X1349175Y-330799D01*
X1350105Y-332049D01*
X1350725Y-333507D01*
X1351035Y-335174D01*
Y-336840D01*
X1350725Y-338507D01*
X1350105Y-339965D01*
X1349175Y-341216D01*
X1348090Y-342049D01*
X1346850Y-342257D01*
G01X1371650Y-329757D02*
Y-342257D01*
G01X1368085Y-329757D02*
X1375215D01*
G01X1380795Y-342257D02*
Y-329757D01*
G01X1387305D02*
Y-342257D01*
G01Y-336007D02*
X1380795D01*
G01X1399550Y-342257D02*
X1393350D01*
Y-329757D01*
X1399550D01*
G01X1397070Y-335799D02*
X1393350D01*
G01X886035Y-319340D02*
X890065D01*
G01X908820Y-323507D02*
Y-311007D01*
X912850Y-321424D01*
X916880Y-311007D01*
Y-323507D01*
G01X921685D02*
Y-311007D01*
X928815Y-323507D01*
Y-311007D01*
G01X941060Y-312049D02*
X940130Y-311424D01*
X939045Y-311007D01*
X937805D01*
X936410Y-311632D01*
X935325Y-312674D01*
X934550Y-313924D01*
X933930Y-316007D01*
X933775Y-317882D01*
X934085Y-319757D01*
X934550Y-321007D01*
X935480Y-322257D01*
X936565Y-323090D01*
X937650Y-323507D01*
X938735D01*
X939820Y-323090D01*
X940750Y-322466D01*
X941525Y-321632D01*
G01X945400Y-327674D02*
X954700D01*
G01X959350Y-311007D02*
Y-323507D01*
X965550D01*
G01X970975D02*
X974850Y-311007D01*
X978725Y-323507D01*
G01X977330Y-319132D02*
X972370D01*
G01X987250Y-323507D02*
Y-317882D01*
X984150Y-311007D01*
G01X990350D02*
X987250Y-317882D01*
G01X1002750Y-323507D02*
X996550D01*
Y-311007D01*
X1002750D01*
G01X1000270Y-317049D02*
X996550D01*
G01X1008950Y-323507D02*
Y-311007D01*
X1012825D01*
X1014065Y-311632D01*
X1014840Y-312465D01*
X1015150Y-314132D01*
X1014840Y-315799D01*
X1013910Y-316840D01*
X1012825Y-317465D01*
X1008950D01*
G01X1012825D02*
X1015150Y-323507D01*
G01X1024450Y-323924D02*
X1024140Y-323715D01*
Y-323299D01*
X1024450Y-323090D01*
X1024760Y-323299D01*
Y-323715D01*
X1024450Y-323924D01*
G01Y-318299D02*
X1024140Y-318090D01*
Y-317674D01*
X1024450Y-317465D01*
X1024760Y-317674D01*
Y-318090D01*
X1024450Y-318299D01*
G01X1045220Y-323507D02*
Y-311007D01*
X1049250Y-321424D01*
X1053280Y-311007D01*
Y-323507D01*
G01X1058240Y-311007D02*
Y-319965D01*
X1058860Y-321841D01*
X1060100Y-323090D01*
X1061650Y-323507D01*
X1063200Y-323090D01*
X1064440Y-321841D01*
X1065060Y-319965D01*
Y-311007D01*
G01X1070795Y-321841D02*
X1072035Y-322882D01*
X1073430Y-323507D01*
X1074670D01*
X1075910Y-322882D01*
X1076840Y-321841D01*
X1077305Y-320382D01*
X1076995Y-318924D01*
X1076220Y-317674D01*
X1074825Y-316840D01*
X1072965Y-316424D01*
X1071880Y-315590D01*
X1071415Y-314132D01*
X1071725Y-312674D01*
X1072500Y-311632D01*
X1073585Y-311007D01*
X1074670D01*
X1075755Y-311424D01*
X1076685Y-312465D01*
G01X1086450Y-311007D02*
Y-323507D01*
G01X1082885Y-311007D02*
X1090015D01*
G01X1096835Y-319340D02*
X1100865D01*
G01X1107685Y-323507D02*
Y-311007D01*
X1114815Y-323507D01*
Y-311007D01*
G01X1123650Y-323507D02*
X1122410Y-323299D01*
X1121325Y-322466D01*
X1120395Y-321215D01*
X1119775Y-319757D01*
X1119465Y-318090D01*
Y-316424D01*
X1119775Y-314757D01*
X1120395Y-313299D01*
X1121325Y-312049D01*
X1122410Y-311215D01*
X1123650Y-311007D01*
X1124890Y-311215D01*
X1125975Y-312049D01*
X1126905Y-313299D01*
X1127525Y-314757D01*
X1127835Y-316424D01*
Y-318090D01*
X1127525Y-319757D01*
X1126905Y-321215D01*
X1125975Y-322466D01*
X1124890Y-323299D01*
X1123650Y-323507D01*
G01X1136050Y-311007D02*
Y-323507D01*
G01X1132485Y-311007D02*
X1139615D01*
G01X1146435Y-319340D02*
X1150465D01*
G01X1164260Y-312049D02*
X1163330Y-311424D01*
X1162245Y-311007D01*
X1161005D01*
X1159610Y-311632D01*
X1158525Y-312674D01*
X1157750Y-313924D01*
X1157130Y-316007D01*
X1156975Y-317882D01*
X1157285Y-319757D01*
X1157750Y-321007D01*
X1158680Y-322257D01*
X1159765Y-323090D01*
X1160850Y-323507D01*
X1161935D01*
X1163020Y-323090D01*
X1163950Y-322466D01*
X1164725Y-321632D01*
G01X1169840Y-311007D02*
Y-319965D01*
X1170460Y-321841D01*
X1171700Y-323090D01*
X1173250Y-323507D01*
X1174800Y-323090D01*
X1176040Y-321841D01*
X1176660Y-319965D01*
Y-311007D01*
G01X1185650D02*
Y-323507D01*
G01X1182085Y-311007D02*
X1189215D01*
G01X1196035Y-319340D02*
X1200065D01*
G01X1207350Y-311007D02*
Y-323507D01*
X1213550D01*
G01X1218975D02*
X1222850Y-311007D01*
X1226725Y-323507D01*
G01X1225330Y-319132D02*
X1220370D01*
G01X1235250Y-323507D02*
Y-317882D01*
X1232150Y-311007D01*
G01X1238350D02*
X1235250Y-317882D01*
G01X1250750Y-323507D02*
X1244550D01*
Y-311007D01*
X1250750D01*
G01X1248270Y-317049D02*
X1244550D01*
G01X1256950Y-323507D02*
Y-311007D01*
X1260825D01*
X1262065Y-311632D01*
X1262840Y-312465D01*
X1263150Y-314132D01*
X1262840Y-315799D01*
X1261910Y-316840D01*
X1260825Y-317465D01*
X1256950D01*
G01X1260825D02*
X1263150Y-323507D01*
G01X884485Y-304757D02*
Y-292257D01*
X891615Y-304757D01*
Y-292257D01*
G01X900450Y-304757D02*
X899210Y-304549D01*
X898125Y-303716D01*
X897195Y-302465D01*
X896575Y-301007D01*
X896265Y-299340D01*
Y-297674D01*
X896575Y-296007D01*
X897195Y-294549D01*
X898125Y-293299D01*
X899210Y-292465D01*
X900450Y-292257D01*
X901690Y-292465D01*
X902775Y-293299D01*
X903705Y-294549D01*
X904325Y-296007D01*
X904635Y-297674D01*
Y-299340D01*
X904325Y-301007D01*
X903705Y-302465D01*
X902775Y-303716D01*
X901690Y-304549D01*
X900450Y-304757D01*
G01X912850Y-292257D02*
Y-304757D01*
G01X909285Y-292257D02*
X916415D01*
G01X928350Y-304757D02*
X922150D01*
Y-292257D01*
X928350D01*
G01X925870Y-298299D02*
X922150D01*
G01X934395Y-303091D02*
X935635Y-304132D01*
X937030Y-304757D01*
X938270D01*
X939510Y-304132D01*
X940440Y-303091D01*
X940905Y-301632D01*
X940595Y-300174D01*
X939820Y-298924D01*
X938425Y-298090D01*
X936565Y-297674D01*
X935480Y-296840D01*
X935015Y-295382D01*
X935325Y-293924D01*
X936100Y-292882D01*
X937185Y-292257D01*
X938270D01*
X939355Y-292674D01*
X940285Y-293715D01*
G01X950050Y-305174D02*
X949740Y-304965D01*
Y-304549D01*
X950050Y-304340D01*
X950360Y-304549D01*
Y-304965D01*
X950050Y-305174D01*
G01Y-299549D02*
X949740Y-299340D01*
Y-298924D01*
X950050Y-298715D01*
X950360Y-298924D01*
Y-299340D01*
X950050Y-299549D01*
G01X883400Y-267257D02*
Y-167257D01*
X1633600D01*
Y-267257D01*
X883400D01*
G01X894405Y-236007D02*
Y-223507D01*
X900295D01*
G01X898125Y-229549D02*
X894405D01*
G01X907890Y-223507D02*
X911610D01*
G01X909750D02*
Y-236007D01*
G01X907890D02*
X911610D01*
G01X923080Y-229757D02*
X926180D01*
Y-233507D01*
X925250Y-234757D01*
X924165Y-235590D01*
X922615Y-236007D01*
X921065Y-235590D01*
X919980Y-234757D01*
X919050Y-233507D01*
X918430Y-232049D01*
X918120Y-230382D01*
Y-228924D01*
X918430Y-227674D01*
X919050Y-226215D01*
X919980Y-224965D01*
X920910Y-224132D01*
X922150Y-223507D01*
X923235D01*
X924475Y-223924D01*
X925405Y-224757D01*
G01X931140Y-223507D02*
Y-232465D01*
X931760Y-234341D01*
X933000Y-235590D01*
X934550Y-236007D01*
X936100Y-235590D01*
X937340Y-234341D01*
X937960Y-232465D01*
Y-223507D01*
G01X943850Y-236007D02*
Y-223507D01*
X947725D01*
X948965Y-224132D01*
X949740Y-224965D01*
X950050Y-226632D01*
X949740Y-228299D01*
X948810Y-229340D01*
X947725Y-229965D01*
X943850D01*
G01X947725D02*
X950050Y-236007D01*
G01X962450D02*
X956250D01*
Y-223507D01*
X962450D01*
G01X959970Y-229549D02*
X956250D01*
G01X883400Y-242257D02*
X1633600D01*
G01X883400Y-217257D02*
X1633600D01*
G01X883400Y-192257D02*
X1633600D01*
G01X973300Y-217257D02*
Y-267257D01*
G01X1000890Y-229340D02*
X1001510Y-228715D01*
X1001975Y-227674D01*
X1002285Y-226215D01*
X1001975Y-224965D01*
X1001355Y-224132D01*
X1000270Y-223507D01*
X996085D01*
Y-236007D01*
X1001200D01*
X1002285Y-235174D01*
X1002905Y-233924D01*
X1003215Y-232465D01*
X1002905Y-231007D01*
X1001975Y-229757D01*
X1000890Y-229340D01*
X996085D01*
G01X1008640Y-236007D02*
Y-223507D01*
X1011740D01*
X1012980Y-224132D01*
X1013910Y-224965D01*
X1014685Y-226215D01*
X1015305Y-227674D01*
X1015460Y-229757D01*
X1015305Y-231840D01*
X1014685Y-233299D01*
X1013910Y-234549D01*
X1012980Y-235382D01*
X1011740Y-236007D01*
X1008640D01*
G01X1019800Y-240174D02*
X1029100D01*
G01X1033595Y-234341D02*
X1034835Y-235382D01*
X1036230Y-236007D01*
X1037470D01*
X1038710Y-235382D01*
X1039640Y-234341D01*
X1040105Y-232882D01*
X1039795Y-231424D01*
X1039020Y-230174D01*
X1037625Y-229340D01*
X1035765Y-228924D01*
X1034680Y-228090D01*
X1034215Y-226632D01*
X1034525Y-225174D01*
X1035300Y-224132D01*
X1036385Y-223507D01*
X1037470D01*
X1038555Y-223924D01*
X1039485Y-224965D01*
G01X1047390Y-223507D02*
X1051110D01*
G01X1049250D02*
Y-236007D01*
G01X1047390D02*
X1051110D01*
G01X1058705Y-223507D02*
X1064595D01*
X1058705Y-236007D01*
X1064595D01*
G01X1077150D02*
X1070950D01*
Y-223507D01*
X1077150D01*
G01X1074670Y-229549D02*
X1070950D01*
G01X1018250Y-261007D02*
Y-248507D01*
X1016390Y-251007D01*
G01Y-261007D02*
X1020110D01*
G01X1027705Y-255799D02*
X1028790Y-254340D01*
X1029720Y-253507D01*
X1030960Y-253090D01*
X1032045Y-253507D01*
X1032820Y-254340D01*
X1033440Y-255590D01*
X1033595Y-257049D01*
X1033440Y-258299D01*
X1032820Y-259549D01*
X1031890Y-260590D01*
X1030805Y-261007D01*
X1029565Y-260590D01*
X1028480Y-259341D01*
X1027860Y-257465D01*
X1027705Y-255382D01*
X1028015Y-252674D01*
X1028480Y-251215D01*
X1029255Y-249757D01*
X1030340Y-248715D01*
X1031425Y-248507D01*
X1032510Y-248924D01*
X1033285Y-249965D01*
G01X1043050Y-261424D02*
X1042740Y-261215D01*
Y-260799D01*
X1043050Y-260590D01*
X1043360Y-260799D01*
Y-261215D01*
X1043050Y-261424D01*
G01X1055450Y-248507D02*
X1054210Y-248924D01*
X1053280Y-249965D01*
X1052660Y-251215D01*
X1052195Y-252882D01*
X1052040Y-254757D01*
X1052195Y-256632D01*
X1052660Y-258299D01*
X1053280Y-259549D01*
X1054210Y-260590D01*
X1055450Y-261007D01*
X1056690Y-260590D01*
X1057620Y-259549D01*
X1058240Y-258299D01*
X1058705Y-256632D01*
X1058860Y-254757D01*
X1058705Y-252882D01*
X1058240Y-251215D01*
X1057620Y-249965D01*
X1056690Y-248924D01*
X1055450Y-248507D01*
G01X1086140Y-179340D02*
X1086760Y-178715D01*
X1087225Y-177674D01*
X1087535Y-176215D01*
X1087225Y-174965D01*
X1086605Y-174132D01*
X1085520Y-173507D01*
X1081335D01*
Y-186007D01*
X1086450D01*
X1087535Y-185174D01*
X1088155Y-183924D01*
X1088465Y-182465D01*
X1088155Y-181007D01*
X1087225Y-179757D01*
X1086140Y-179340D01*
X1081335D01*
G01X1093425Y-186007D02*
X1097300Y-173507D01*
X1101175Y-186007D01*
G01X1099780Y-181632D02*
X1094820D01*
G01X1113110Y-174549D02*
X1112180Y-173924D01*
X1111095Y-173507D01*
X1109855D01*
X1108460Y-174132D01*
X1107375Y-175174D01*
X1106600Y-176424D01*
X1105980Y-178507D01*
X1105825Y-180382D01*
X1106135Y-182257D01*
X1106600Y-183507D01*
X1107530Y-184757D01*
X1108615Y-185590D01*
X1109700Y-186007D01*
X1110785D01*
X1111870Y-185590D01*
X1112800Y-184966D01*
X1113575Y-184132D01*
G01X1118690Y-186007D02*
Y-173507D01*
G01X1124580D02*
X1118690Y-181216D01*
G01X1125510Y-186007D02*
X1121325Y-177674D01*
G01X1131090Y-186007D02*
Y-173507D01*
X1134190D01*
X1135430Y-174132D01*
X1136360Y-174965D01*
X1137135Y-176215D01*
X1137755Y-177674D01*
X1137910Y-179757D01*
X1137755Y-181840D01*
X1137135Y-183299D01*
X1136360Y-184549D01*
X1135430Y-185382D01*
X1134190Y-186007D01*
X1131090D01*
G01X1143800D02*
Y-173507D01*
X1147675D01*
X1148915Y-174132D01*
X1149690Y-174965D01*
X1150000Y-176632D01*
X1149690Y-178299D01*
X1148760Y-179340D01*
X1147675Y-179965D01*
X1143800D01*
G01X1147675D02*
X1150000Y-186007D01*
G01X1157440Y-173507D02*
X1161160D01*
G01X1159300D02*
Y-186007D01*
G01X1157440D02*
X1161160D01*
G01X1168600Y-173507D02*
Y-186007D01*
X1174800D01*
G01X1181000Y-173507D02*
Y-186007D01*
X1187200D01*
G01X1196500Y-186424D02*
X1196190Y-186215D01*
Y-185799D01*
X1196500Y-185590D01*
X1196810Y-185799D01*
Y-186215D01*
X1196500Y-186424D01*
G01Y-180799D02*
X1196190Y-180590D01*
Y-180174D01*
X1196500Y-179965D01*
X1196810Y-180174D01*
Y-180590D01*
X1196500Y-180799D01*
G01X1222540Y-179340D02*
X1223160Y-178715D01*
X1223625Y-177674D01*
X1223935Y-176215D01*
X1223625Y-174965D01*
X1223005Y-174132D01*
X1221920Y-173507D01*
X1217735D01*
Y-186007D01*
X1222850D01*
X1223935Y-185174D01*
X1224555Y-183924D01*
X1224865Y-182465D01*
X1224555Y-181007D01*
X1223625Y-179757D01*
X1222540Y-179340D01*
X1217735D01*
G01X1233700Y-186007D02*
X1232460Y-185799D01*
X1231375Y-184966D01*
X1230445Y-183715D01*
X1229825Y-182257D01*
X1229515Y-180590D01*
Y-178924D01*
X1229825Y-177257D01*
X1230445Y-175799D01*
X1231375Y-174549D01*
X1232460Y-173715D01*
X1233700Y-173507D01*
X1234940Y-173715D01*
X1236025Y-174549D01*
X1236955Y-175799D01*
X1237575Y-177257D01*
X1237885Y-178924D01*
Y-180590D01*
X1237575Y-182257D01*
X1236955Y-183715D01*
X1236025Y-184966D01*
X1234940Y-185799D01*
X1233700Y-186007D01*
G01X1246100Y-173507D02*
Y-186007D01*
G01X1242535Y-173507D02*
X1249665D01*
G01X1258500D02*
Y-186007D01*
G01X1254935Y-173507D02*
X1262065D01*
G01X1270900Y-186007D02*
X1269660Y-185799D01*
X1268575Y-184966D01*
X1267645Y-183715D01*
X1267025Y-182257D01*
X1266715Y-180590D01*
Y-178924D01*
X1267025Y-177257D01*
X1267645Y-175799D01*
X1268575Y-174549D01*
X1269660Y-173715D01*
X1270900Y-173507D01*
X1272140Y-173715D01*
X1273225Y-174549D01*
X1274155Y-175799D01*
X1274775Y-177257D01*
X1275085Y-178924D01*
Y-180590D01*
X1274775Y-182257D01*
X1274155Y-183715D01*
X1273225Y-184966D01*
X1272140Y-185799D01*
X1270900Y-186007D01*
G01X1279270D02*
Y-173507D01*
X1283300Y-183924D01*
X1287330Y-173507D01*
Y-186007D01*
G01X1308100Y-173507D02*
Y-186007D01*
G01X1305930Y-177674D02*
X1310270D01*
G01X1320500Y-186007D02*
X1319570Y-185799D01*
X1318640Y-184966D01*
X1318020Y-183507D01*
X1317710Y-181840D01*
X1318020Y-180174D01*
X1318640Y-178715D01*
X1319570Y-177882D01*
X1320500Y-177674D01*
X1321430Y-177882D01*
X1322360Y-178715D01*
X1322980Y-180174D01*
X1323135Y-181840D01*
X1322980Y-183507D01*
X1322360Y-184966D01*
X1321430Y-185799D01*
X1320500Y-186007D01*
G01X1342200Y-173507D02*
Y-186007D01*
X1348400D01*
G01X1357700Y-173507D02*
X1356460Y-173924D01*
X1355530Y-174965D01*
X1354910Y-176215D01*
X1354445Y-177882D01*
X1354290Y-179757D01*
X1354445Y-181632D01*
X1354910Y-183299D01*
X1355530Y-184549D01*
X1356460Y-185590D01*
X1357700Y-186007D01*
X1358940Y-185590D01*
X1359870Y-184549D01*
X1360490Y-183299D01*
X1360955Y-181632D01*
X1361110Y-179757D01*
X1360955Y-177882D01*
X1360490Y-176215D01*
X1359870Y-174965D01*
X1358940Y-173924D01*
X1357700Y-173507D01*
G01X1367465Y-184549D02*
X1368550Y-185590D01*
X1369790Y-186007D01*
X1371030Y-185590D01*
X1372115Y-184341D01*
X1372890Y-182465D01*
X1373200Y-180590D01*
Y-178299D01*
X1372890Y-176424D01*
X1372115Y-174757D01*
X1371185Y-173924D01*
X1370100Y-173507D01*
X1368860Y-173924D01*
X1367930Y-174757D01*
X1367310Y-176007D01*
X1367000Y-177674D01*
X1367310Y-179132D01*
X1368085Y-180590D01*
X1369015Y-181424D01*
X1370100Y-181632D01*
X1371340Y-181216D01*
X1372270Y-180174D01*
X1373200Y-178299D01*
G01X1377850Y-190174D02*
X1387150D01*
G01X1395830Y-179757D02*
X1398930D01*
Y-183507D01*
X1398000Y-184757D01*
X1396915Y-185590D01*
X1395365Y-186007D01*
X1393815Y-185590D01*
X1392730Y-184757D01*
X1391800Y-183507D01*
X1391180Y-182049D01*
X1390870Y-180382D01*
Y-178924D01*
X1391180Y-177674D01*
X1391800Y-176215D01*
X1392730Y-174965D01*
X1393660Y-174132D01*
X1394900Y-173507D01*
X1395985D01*
X1397225Y-173924D01*
X1398155Y-174757D01*
G01X1403735Y-186007D02*
Y-173507D01*
X1410865Y-186007D01*
Y-173507D01*
G01X1416290Y-186007D02*
Y-173507D01*
X1419390D01*
X1420630Y-174132D01*
X1421560Y-174965D01*
X1422335Y-176215D01*
X1422955Y-177674D01*
X1423110Y-179757D01*
X1422955Y-181840D01*
X1422335Y-183299D01*
X1421560Y-184549D01*
X1420630Y-185382D01*
X1419390Y-186007D01*
X1416290D01*
G01X1433960D02*
Y-173507D01*
X1428225Y-182465D01*
X1435975D01*
G01X1100400Y-217257D02*
Y-267257D01*
G01X1130625Y-211007D02*
X1134500Y-198507D01*
X1138375Y-211007D01*
G01X1136980Y-206632D02*
X1132020D01*
G01X1143800Y-198507D02*
Y-211007D01*
X1150000D01*
G01X1156200Y-198507D02*
Y-211007D01*
X1162400D01*
G01X1180690Y-198507D02*
Y-207465D01*
X1181310Y-209341D01*
X1182550Y-210590D01*
X1184100Y-211007D01*
X1185650Y-210590D01*
X1186890Y-209341D01*
X1187510Y-207465D01*
Y-198507D01*
G01X1192935Y-211007D02*
Y-198507D01*
X1200065Y-211007D01*
Y-198507D01*
G01X1207040D02*
X1210760D01*
G01X1208900D02*
Y-211007D01*
G01X1207040D02*
X1210760D01*
G01X1221300Y-198507D02*
Y-211007D01*
G01X1217735Y-198507D02*
X1224865D01*
G01X1230445Y-209341D02*
X1231685Y-210382D01*
X1233080Y-211007D01*
X1234320D01*
X1235560Y-210382D01*
X1236490Y-209341D01*
X1236955Y-207882D01*
X1236645Y-206424D01*
X1235870Y-205174D01*
X1234475Y-204340D01*
X1232615Y-203924D01*
X1231530Y-203090D01*
X1231065Y-201632D01*
X1231375Y-200174D01*
X1232150Y-199132D01*
X1233235Y-198507D01*
X1234320D01*
X1235405Y-198924D01*
X1236335Y-199965D01*
G01X1254625Y-211007D02*
X1258500Y-198507D01*
X1262375Y-211007D01*
G01X1260980Y-206632D02*
X1256020D01*
G01X1267800Y-211007D02*
Y-198507D01*
X1271675D01*
X1272915Y-199132D01*
X1273690Y-199965D01*
X1274000Y-201632D01*
X1273690Y-203299D01*
X1272760Y-204340D01*
X1271675Y-204965D01*
X1267800D01*
G01X1271675D02*
X1274000Y-211007D01*
G01X1286400D02*
X1280200D01*
Y-198507D01*
X1286400D01*
G01X1283920Y-204549D02*
X1280200D01*
G01X1306240Y-198507D02*
X1309960D01*
G01X1308100D02*
Y-211007D01*
G01X1306240D02*
X1309960D01*
G01X1316935D02*
Y-198507D01*
X1324065Y-211007D01*
Y-198507D01*
G01X1341270Y-211007D02*
Y-198507D01*
X1345300Y-208924D01*
X1349330Y-198507D01*
Y-211007D01*
G01X1355840Y-198507D02*
X1359560D01*
G01X1357700D02*
Y-211007D01*
G01X1355840D02*
X1359560D01*
G01X1367000Y-198507D02*
Y-211007D01*
X1373200D01*
G01X1379245Y-209341D02*
X1380485Y-210382D01*
X1381880Y-211007D01*
X1383120D01*
X1384360Y-210382D01*
X1385290Y-209341D01*
X1385755Y-207882D01*
X1385445Y-206424D01*
X1384670Y-205174D01*
X1383275Y-204340D01*
X1381415Y-203924D01*
X1380330Y-203090D01*
X1379865Y-201632D01*
X1380175Y-200174D01*
X1380950Y-199132D01*
X1382035Y-198507D01*
X1383120D01*
X1384205Y-198924D01*
X1385135Y-199965D01*
G01X1154650Y-248507D02*
Y-261007D01*
X1160850D01*
G01X1170150Y-248507D02*
X1168910Y-248924D01*
X1167980Y-249965D01*
X1167360Y-251215D01*
X1166895Y-252882D01*
X1166740Y-254757D01*
X1166895Y-256632D01*
X1167360Y-258299D01*
X1167980Y-259549D01*
X1168910Y-260590D01*
X1170150Y-261007D01*
X1171390Y-260590D01*
X1172320Y-259549D01*
X1172940Y-258299D01*
X1173405Y-256632D01*
X1173560Y-254757D01*
X1173405Y-252882D01*
X1172940Y-251215D01*
X1172320Y-249965D01*
X1171390Y-248924D01*
X1170150Y-248507D01*
G01X1182550Y-261007D02*
X1183635Y-260799D01*
X1184875Y-260174D01*
X1185650Y-259132D01*
X1185960Y-257674D01*
X1185650Y-256216D01*
X1184720Y-254965D01*
X1183325Y-254340D01*
X1181775D01*
X1180845Y-253924D01*
X1180070Y-252882D01*
X1179760Y-251424D01*
X1180225Y-249965D01*
X1181310Y-248924D01*
X1182550Y-248507D01*
X1183790Y-248924D01*
X1184875Y-249965D01*
X1185340Y-251424D01*
X1185030Y-252882D01*
X1184255Y-253924D01*
X1183325Y-254340D01*
X1181775D01*
X1180380Y-254965D01*
X1179450Y-256216D01*
X1179140Y-257674D01*
X1179450Y-259132D01*
X1180225Y-260174D01*
X1181465Y-260799D01*
X1182550Y-261007D01*
G01X1190300Y-265174D02*
X1199600D01*
G01X1204095Y-259341D02*
X1205335Y-260382D01*
X1206730Y-261007D01*
X1207970D01*
X1209210Y-260382D01*
X1210140Y-259341D01*
X1210605Y-257882D01*
X1210295Y-256424D01*
X1209520Y-255174D01*
X1208125Y-254340D01*
X1206265Y-253924D01*
X1205180Y-253090D01*
X1204715Y-251632D01*
X1205025Y-250174D01*
X1205800Y-249132D01*
X1206885Y-248507D01*
X1207970D01*
X1209055Y-248924D01*
X1209985Y-249965D01*
G01X1217890Y-248507D02*
X1221610D01*
G01X1219750D02*
Y-261007D01*
G01X1217890D02*
X1221610D01*
G01X1233080Y-254757D02*
X1236180D01*
Y-258507D01*
X1235250Y-259757D01*
X1234165Y-260590D01*
X1232615Y-261007D01*
X1231065Y-260590D01*
X1229980Y-259757D01*
X1229050Y-258507D01*
X1228430Y-257049D01*
X1228120Y-255382D01*
Y-253924D01*
X1228430Y-252674D01*
X1229050Y-251215D01*
X1229980Y-249965D01*
X1230910Y-249132D01*
X1232150Y-248507D01*
X1233235D01*
X1234475Y-248924D01*
X1235405Y-249757D01*
G01X1241605Y-250590D02*
X1242535Y-249341D01*
X1243620Y-248715D01*
X1244860Y-248507D01*
X1246410Y-248924D01*
X1247495Y-249965D01*
X1247805Y-251215D01*
X1247650Y-252466D01*
X1247030Y-253507D01*
X1243930Y-255590D01*
X1242535Y-257049D01*
X1241605Y-259132D01*
X1241295Y-261007D01*
X1247805D01*
G01X1147520Y-236007D02*
Y-223507D01*
X1151550Y-233924D01*
X1155580Y-223507D01*
Y-236007D01*
G01X1160385D02*
Y-223507D01*
X1167515Y-236007D01*
Y-223507D01*
G01X1179760Y-224549D02*
X1178830Y-223924D01*
X1177745Y-223507D01*
X1176505D01*
X1175110Y-224132D01*
X1174025Y-225174D01*
X1173250Y-226424D01*
X1172630Y-228507D01*
X1172475Y-230382D01*
X1172785Y-232257D01*
X1173250Y-233507D01*
X1174180Y-234757D01*
X1175265Y-235590D01*
X1176350Y-236007D01*
X1177435D01*
X1178520Y-235590D01*
X1179450Y-234966D01*
X1180225Y-234132D01*
G01X1184100Y-240174D02*
X1193400D01*
G01X1198050Y-223507D02*
Y-236007D01*
X1204250D01*
G01X1209675D02*
X1213550Y-223507D01*
X1217425Y-236007D01*
G01X1216030Y-231632D02*
X1211070D01*
G01X1225950Y-236007D02*
Y-230382D01*
X1222850Y-223507D01*
G01X1229050D02*
X1225950Y-230382D01*
G01X1241450Y-236007D02*
X1235250D01*
Y-223507D01*
X1241450D01*
G01X1238970Y-229549D02*
X1235250D01*
G01X1247650Y-236007D02*
Y-223507D01*
X1251525D01*
X1252765Y-224132D01*
X1253540Y-224965D01*
X1253850Y-226632D01*
X1253540Y-228299D01*
X1252610Y-229340D01*
X1251525Y-229965D01*
X1247650D01*
G01X1251525D02*
X1253850Y-236007D01*
G01X1301900Y-217257D02*
Y-267257D01*
G01X1311820Y-236007D02*
Y-223507D01*
X1315850Y-233924D01*
X1319880Y-223507D01*
Y-236007D01*
G01X1324375D02*
X1328250Y-223507D01*
X1332125Y-236007D01*
G01X1330730Y-231632D02*
X1325770D01*
G01X1337395Y-236007D02*
X1343905Y-223507D01*
G01X1337395D02*
X1343905Y-236007D01*
G01X1348400Y-240174D02*
X1357700D01*
G01X1362040Y-236007D02*
Y-223507D01*
X1365140D01*
X1366380Y-224132D01*
X1367310Y-224965D01*
X1368085Y-226215D01*
X1368705Y-227674D01*
X1368860Y-229757D01*
X1368705Y-231840D01*
X1368085Y-233299D01*
X1367310Y-234549D01*
X1366380Y-235382D01*
X1365140Y-236007D01*
X1362040D01*
G01X1380950D02*
X1374750D01*
Y-223507D01*
X1380950D01*
G01X1378470Y-229549D02*
X1374750D01*
G01X1387150Y-236007D02*
Y-223507D01*
X1390870D01*
X1392110Y-224132D01*
X1393040Y-225590D01*
X1393350Y-227257D01*
X1393040Y-228924D01*
X1392265Y-230174D01*
X1390870Y-230799D01*
X1387150D01*
G01X1402650Y-223507D02*
Y-236007D01*
G01X1399085Y-223507D02*
X1406215D01*
G01X1411795Y-236007D02*
Y-223507D01*
G01X1418305D02*
Y-236007D01*
G01Y-229757D02*
X1411795D01*
G01X1346850Y-261007D02*
Y-248507D01*
X1344990Y-251007D01*
G01Y-261007D02*
X1348710D01*
G01X1359250Y-248507D02*
X1358010Y-248924D01*
X1357080Y-249965D01*
X1356460Y-251215D01*
X1355995Y-252882D01*
X1355840Y-254757D01*
X1355995Y-256632D01*
X1356460Y-258299D01*
X1357080Y-259549D01*
X1358010Y-260590D01*
X1359250Y-261007D01*
X1360490Y-260590D01*
X1361420Y-259549D01*
X1362040Y-258299D01*
X1362505Y-256632D01*
X1362660Y-254757D01*
X1362505Y-252882D01*
X1362040Y-251215D01*
X1361420Y-249965D01*
X1360490Y-248924D01*
X1359250Y-248507D01*
G01X1371650Y-261424D02*
X1371340Y-261215D01*
Y-260799D01*
X1371650Y-260590D01*
X1371960Y-260799D01*
Y-261215D01*
X1371650Y-261424D01*
G01X1385910Y-261007D02*
Y-248507D01*
X1380175Y-257465D01*
X1387925D01*
G01X1380850Y-273507D02*
Y-286007D01*
G01X1377285Y-273507D02*
X1384415D01*
G01X1393250Y-286007D02*
X1392010Y-285799D01*
X1390925Y-284966D01*
X1389995Y-283715D01*
X1389375Y-282257D01*
X1389065Y-280590D01*
Y-278924D01*
X1389375Y-277257D01*
X1389995Y-275799D01*
X1390925Y-274549D01*
X1392010Y-273715D01*
X1393250Y-273507D01*
X1394490Y-273715D01*
X1395575Y-274549D01*
X1396505Y-275799D01*
X1397125Y-277257D01*
X1397435Y-278924D01*
Y-280590D01*
X1397125Y-282257D01*
X1396505Y-283715D01*
X1395575Y-284966D01*
X1394490Y-285799D01*
X1393250Y-286007D01*
G01X1405650Y-273507D02*
Y-286007D01*
G01X1402085Y-273507D02*
X1409215D01*
G01X1414175Y-286007D02*
X1418050Y-273507D01*
X1421925Y-286007D01*
G01X1420530Y-281632D02*
X1415570D01*
G01X1427350Y-273507D02*
Y-286007D01*
X1433550D01*
G01X1456490Y-279340D02*
X1457110Y-278715D01*
X1457575Y-277674D01*
X1457885Y-276215D01*
X1457575Y-274965D01*
X1456955Y-274132D01*
X1455870Y-273507D01*
X1451685D01*
Y-286007D01*
X1456800D01*
X1457885Y-285174D01*
X1458505Y-283924D01*
X1458815Y-282465D01*
X1458505Y-281007D01*
X1457575Y-279757D01*
X1456490Y-279340D01*
X1451685D01*
G01X1463775Y-286007D02*
X1467650Y-273507D01*
X1471525Y-286007D01*
G01X1470130Y-281632D02*
X1465170D01*
G01X1483460Y-274549D02*
X1482530Y-273924D01*
X1481445Y-273507D01*
X1480205D01*
X1478810Y-274132D01*
X1477725Y-275174D01*
X1476950Y-276424D01*
X1476330Y-278507D01*
X1476175Y-280382D01*
X1476485Y-282257D01*
X1476950Y-283507D01*
X1477880Y-284757D01*
X1478965Y-285590D01*
X1480050Y-286007D01*
X1481135D01*
X1482220Y-285590D01*
X1483150Y-284966D01*
X1483925Y-284132D01*
G01X1489040Y-286007D02*
Y-273507D01*
G01X1494930D02*
X1489040Y-281216D01*
G01X1495860Y-286007D02*
X1491675Y-277674D01*
G01X1501440Y-286007D02*
Y-273507D01*
X1504540D01*
X1505780Y-274132D01*
X1506710Y-274965D01*
X1507485Y-276215D01*
X1508105Y-277674D01*
X1508260Y-279757D01*
X1508105Y-281840D01*
X1507485Y-283299D01*
X1506710Y-284549D01*
X1505780Y-285382D01*
X1504540Y-286007D01*
X1501440D01*
G01X1514150D02*
Y-273507D01*
X1518025D01*
X1519265Y-274132D01*
X1520040Y-274965D01*
X1520350Y-276632D01*
X1520040Y-278299D01*
X1519110Y-279340D01*
X1518025Y-279965D01*
X1514150D01*
G01X1518025D02*
X1520350Y-286007D01*
G01X1527790Y-273507D02*
X1531510D01*
G01X1529650D02*
Y-286007D01*
G01X1527790D02*
X1531510D01*
G01X1538950Y-273507D02*
Y-286007D01*
X1545150D01*
G01X1551350Y-273507D02*
Y-286007D01*
X1557550D01*
G01X1563595Y-284341D02*
X1564835Y-285382D01*
X1566230Y-286007D01*
X1567470D01*
X1568710Y-285382D01*
X1569640Y-284341D01*
X1570105Y-282882D01*
X1569795Y-281424D01*
X1569020Y-280174D01*
X1567625Y-279340D01*
X1565765Y-278924D01*
X1564680Y-278090D01*
X1564215Y-276632D01*
X1564525Y-275174D01*
X1565300Y-274132D01*
X1566385Y-273507D01*
X1567470D01*
X1568555Y-273924D01*
X1569485Y-274965D01*
G01X1579250Y-286424D02*
X1578940Y-286215D01*
Y-285799D01*
X1579250Y-285590D01*
X1579560Y-285799D01*
Y-286215D01*
X1579250Y-286424D01*
G01Y-280799D02*
X1578940Y-280590D01*
Y-280174D01*
X1579250Y-279965D01*
X1579560Y-280174D01*
Y-280590D01*
X1579250Y-280799D01*
G01X1601105Y-275590D02*
X1602035Y-274341D01*
X1603120Y-273715D01*
X1604360Y-273507D01*
X1605910Y-273924D01*
X1606995Y-274965D01*
X1607305Y-276215D01*
X1607150Y-277466D01*
X1606530Y-278507D01*
X1603430Y-280590D01*
X1602035Y-282049D01*
X1601105Y-284132D01*
X1600795Y-286007D01*
X1607305D01*
G01X1613505Y-280799D02*
X1614590Y-279340D01*
X1615520Y-278507D01*
X1616760Y-278090D01*
X1617845Y-278507D01*
X1618620Y-279340D01*
X1619240Y-280590D01*
X1619395Y-282049D01*
X1619240Y-283299D01*
X1618620Y-284549D01*
X1617690Y-285590D01*
X1616605Y-286007D01*
X1615365Y-285590D01*
X1614280Y-284341D01*
X1613660Y-282465D01*
X1613505Y-280382D01*
X1613815Y-277674D01*
X1614280Y-276215D01*
X1615055Y-274757D01*
X1616140Y-273715D01*
X1617225Y-273507D01*
X1618310Y-273924D01*
X1619085Y-274965D01*
G01X1429000Y-217257D02*
Y-267257D01*
G01X1445120Y-236007D02*
Y-223507D01*
X1449150Y-233924D01*
X1453180Y-223507D01*
Y-236007D01*
G01X1458605D02*
Y-223507D01*
X1464495D01*
G01X1462325Y-229549D02*
X1458605D01*
G01X1474880Y-229757D02*
X1477980D01*
Y-233507D01*
X1477050Y-234757D01*
X1475965Y-235590D01*
X1474415Y-236007D01*
X1472865Y-235590D01*
X1471780Y-234757D01*
X1470850Y-233507D01*
X1470230Y-232049D01*
X1469920Y-230382D01*
Y-228924D01*
X1470230Y-227674D01*
X1470850Y-226215D01*
X1471780Y-224965D01*
X1472710Y-224132D01*
X1473950Y-223507D01*
X1475035D01*
X1476275Y-223924D01*
X1477205Y-224757D01*
G01X1481700Y-240174D02*
X1491000D01*
G01X1495495Y-234341D02*
X1496735Y-235382D01*
X1498130Y-236007D01*
X1499370D01*
X1500610Y-235382D01*
X1501540Y-234341D01*
X1502005Y-232882D01*
X1501695Y-231424D01*
X1500920Y-230174D01*
X1499525Y-229340D01*
X1497665Y-228924D01*
X1496580Y-228090D01*
X1496115Y-226632D01*
X1496425Y-225174D01*
X1497200Y-224132D01*
X1498285Y-223507D01*
X1499370D01*
X1500455Y-223924D01*
X1501385Y-224965D01*
G01X1511150Y-223507D02*
Y-236007D01*
G01X1507585Y-223507D02*
X1514715D01*
G01X1520140D02*
Y-232465D01*
X1520760Y-234341D01*
X1522000Y-235590D01*
X1523550Y-236007D01*
X1525100Y-235590D01*
X1526340Y-234341D01*
X1526960Y-232465D01*
Y-223507D01*
G01X1537190Y-229340D02*
X1537810Y-228715D01*
X1538275Y-227674D01*
X1538585Y-226215D01*
X1538275Y-224965D01*
X1537655Y-224132D01*
X1536570Y-223507D01*
X1532385D01*
Y-236007D01*
X1537500D01*
X1538585Y-235174D01*
X1539205Y-233924D01*
X1539515Y-232465D01*
X1539205Y-231007D01*
X1538275Y-229757D01*
X1537190Y-229340D01*
X1532385D01*
G01X1490535Y-256840D02*
X1494565D01*
G01X1556100Y-217257D02*
Y-267257D01*
G01X1582450Y-236007D02*
X1581210Y-235799D01*
X1580125Y-234966D01*
X1579195Y-233715D01*
X1578575Y-232257D01*
X1578265Y-230590D01*
Y-228924D01*
X1578575Y-227257D01*
X1579195Y-225799D01*
X1580125Y-224549D01*
X1581210Y-223715D01*
X1582450Y-223507D01*
X1583690Y-223715D01*
X1584775Y-224549D01*
X1585705Y-225799D01*
X1586325Y-227257D01*
X1586635Y-228924D01*
Y-230590D01*
X1586325Y-232257D01*
X1585705Y-233715D01*
X1584775Y-234966D01*
X1583690Y-235799D01*
X1582450Y-236007D01*
G01X1583690Y-232674D02*
X1585550Y-236007D01*
G01X1594850Y-223507D02*
Y-236007D01*
G01X1591285Y-223507D02*
X1598415D01*
G01X1607250Y-236007D02*
Y-230382D01*
X1604150Y-223507D01*
G01X1610350D02*
X1607250Y-230382D01*
G01X1585705Y-250590D02*
X1586635Y-249341D01*
X1587720Y-248715D01*
X1588960Y-248507D01*
X1590510Y-248924D01*
X1591595Y-249965D01*
X1591905Y-251215D01*
X1591750Y-252466D01*
X1591130Y-253507D01*
X1588030Y-255590D01*
X1586635Y-257049D01*
X1585705Y-259132D01*
X1585395Y-261007D01*
X1591905D01*
G01X1598105Y-255799D02*
X1599190Y-254340D01*
X1600120Y-253507D01*
X1601360Y-253090D01*
X1602445Y-253507D01*
X1603220Y-254340D01*
X1603840Y-255590D01*
X1603995Y-257049D01*
X1603840Y-258299D01*
X1603220Y-259549D01*
X1602290Y-260590D01*
X1601205Y-261007D01*
X1599965Y-260590D01*
X1598880Y-259341D01*
X1598260Y-257465D01*
X1598105Y-255382D01*
X1598415Y-252674D01*
X1598880Y-251215D01*
X1599655Y-249757D01*
X1600740Y-248715D01*
X1601825Y-248507D01*
X1602910Y-248924D01*
X1603685Y-249965D01*
M02*
